# S9S_MB_2U (Grand Teton) — schematic netlist excerpt (pin names and nets, part order shuffled) for the footprints in the layout excerpt that follows; sources: Cadence DE-HDL packaged netlist, KiCad conversion of 03242023_DA0F0TMBIJ0_F0T_Motherboard_J_brd_V01_OCP.brd

C1817  Q_CAP  0.1UF 25V 10% X7R  pkg 0402  page 164 : A = P3V3_AUX ; B = GND
R4305  Q_RES  0 5% CHIP  pkg 0402LF  page 179 : A = CLK_100M_PE_M2_0_R_DP ; B = CLK_100M_PE_M2_0_DP
C2284  Q_CAP  22UF 16V 20% X6S  pkg C0805  page 169 : A = P3V3_AUX_USB_BUF ; B = GND

(kicad_pcb
	(version 20260206)
	(generator "pcbnew")
	(generator_version "10.0")
	(general
		(thickness 1.6)
		(legacy_teardrops no)
	)
	(paper "A4")
	(title_block
		(title "03242023_DA0F0TMBIJ0_F0T_Motherboard_J_brd_V01_OCP.brd")
		(comment 1 "Grand Teton / footprints 2286-2288 of 6105")
	)
	(layers
		(0 "F.Cu" signal "TOP")
		(4 "In1.Cu" signal "GND")
		(6 "In2.Cu" signal "IN1")
		(8 "In3.Cu" signal "GND1")
		(10 "In4.Cu" signal "IN2")
		(12 "In5.Cu" signal "GND2")
		(14 "In6.Cu" signal "IN3")
		(16 "In7.Cu" signal "GND3")
		(18 "In8.Cu" signal "VCC")
		(20 "In9.Cu" signal "VCC1")
		(22 "In10.Cu" signal "GND4")
		(24 "In11.Cu" signal "IN4")
		(26 "In12.Cu" signal "GND5")
		(28 "In13.Cu" signal "IN5")
		(30 "In14.Cu" signal "GND6")
		(32 "In15.Cu" signal "IN6")
		(34 "In16.Cu" signal "GND7")
		(2 "B.Cu" signal "BOTTOM")
		(9 "F.Adhes" user "F.Adhesive")
		(11 "B.Adhes" user "B.Adhesive")
		(13 "F.Paste" user "Package Geometry/Pastemask Top")
		(15 "B.Paste" user "Package Geometry/Pastemask Bottom")
		(5 "F.SilkS" user "Ref Des/Silkscreen Top")
		(7 "B.SilkS" user "Ref Des/Silkscreen Bottom")
		(1 "F.Mask" user "Board Geometry/Soldermask Top")
		(3 "B.Mask" user "Board Geometry/Soldermask Bottom")
		(17 "Dwgs.User" user "User.Drawings")
		(19 "Cmts.User" user "User.Comments")
		(21 "Eco1.User" user "User.Eco1")
		(23 "Eco2.User" user "User.Eco2")
		(25 "Edge.Cuts" user "Board Geometry/Outline")
		(27 "Margin" user)
		(31 "F.CrtYd" user "Package Geometry/Place Bound Top")
		(29 "B.CrtYd" user "Package Geometry/Place Bound Bottom")
		(35 "F.Fab" user "Ref Des/Assembly Top")
		(33 "B.Fab" user "Ref Des/Assembly Bottom")
	)
	(footprint ""
		(layer "F.Cu")
		(at 331.099668 -76.153518 90)
		(property "Reference" "R4305"
			(at 0 0 90)
			(layer "F.SilkS")
			(hide yes)
			(effects
				(font
					(size 1.27 1.27)
				)
			)
		)
		(property "Value" ""
			(at 0 0 90)
			(layer "F.Fab")
			(effects
				(font
					(size 1.27 1.27)
				)
			)
		)
		(duplicate_pad_numbers_are_jumpers no)
		(fp_line
			(start 0.7874 -0.4064)
			(end 0.7874 0.4064)
			(stroke
				(width 0.1524)
				(type default)
			)
			(layer "F.SilkS")
		)
		(fp_line
			(start -0.7874 -0.4064)
			(end 0.7874 -0.4064)
			(stroke
				(width 0.1524)
				(type default)
			)
			(layer "F.SilkS")
		)
		(fp_line
			(start 0.7874 0.4064)
			(end -0.7874 0.4064)
			(stroke
				(width 0.1524)
				(type default)
			)
			(layer "F.SilkS")
		)
		(fp_line
			(start -0.7874 0.4064)
			(end -0.7874 -0.4064)
			(stroke
				(width 0.1524)
				(type default)
			)
			(layer "F.SilkS")
		)
		(fp_line
			(start -0.12065 -0.305054)
			(end -0.12065 -0.2794)
			(stroke
				(width 0.1)
				(type default)
			)
			(layer "F.Fab")
		)
		(fp_line
			(start -0.67945 -0.305054)
			(end -0.12065 -0.305054)
			(stroke
				(width 0.1)
				(type default)
			)
			(layer "F.Fab")
		)
		(fp_line
			(start 0.67945 -0.3048)
			(end 0.67945 0.3048)
			(stroke
				(width 0.1)
				(type default)
			)
			(layer "F.Fab")
		)
		(fp_line
			(start 0.12065 -0.3048)
			(end 0.67945 -0.3048)
			(stroke
				(width 0.1)
				(type default)
			)
			(layer "F.Fab")
		)
		(fp_line
			(start 0.12065 -0.2794)
			(end 0.12065 -0.3048)
			(stroke
				(width 0.1)
				(type default)
			)
			(layer "F.Fab")
		)
		(fp_line
			(start -0.12065 -0.2794)
			(end 0.12065 -0.2794)
			(stroke
				(width 0.1)
				(type default)
			)
			(layer "F.Fab")
		)
		(fp_line
			(start 0.120396 0.2794)
			(end -0.12065 0.2794)
			(stroke
				(width 0.1)
				(type default)
			)
			(layer "F.Fab")
		)
		(fp_line
			(start -0.12065 0.2794)
			(end -0.12065 0.3048)
			(stroke
				(width 0.1)
				(type default)
			)
			(layer "F.Fab")
		)
		(fp_line
			(start 0.67945 0.3048)
			(end 0.120396 0.3048)
			(stroke
				(width 0.1)
				(type default)
			)
			(layer "F.Fab")
		)
		(fp_line
			(start 0.120396 0.3048)
			(end 0.120396 0.2794)
			(stroke
				(width 0.1)
				(type default)
			)
			(layer "F.Fab")
		)
		(fp_line
			(start -0.12065 0.3048)
			(end -0.67945 0.3048)
			(stroke
				(width 0.1)
				(type default)
			)
			(layer "F.Fab")
		)
		(fp_line
			(start -0.67945 0.3048)
			(end -0.67945 -0.305054)
			(stroke
				(width 0.1)
				(type default)
			)
			(layer "F.Fab")
		)
		(pad "1" smd circle
			(at -0.40005 0 90)
			(size 0 0)
			(layers "F.Cu" "F.Mask" "F.Paste")
			(net "CLK_100M_PE_M2_0_R_DP")
		)
		(pad "2" smd circle
			(at 0.40005 0 90)
			(size 0 0)
			(layers "F.Cu" "F.Mask" "F.Paste")
			(net "CLK_100M_PE_M2_0_DP")
		)
	)
	(footprint ""
		(layer "F.Cu")
		(at 144.88541 -126.630684)
		(property "Reference" "C1817"
			(at 0 0 0)
			(layer "F.SilkS")
			(hide yes)
			(effects
				(font
					(size 1.27 1.27)
				)
			)
		)
		(property "Value" ""
			(at 0 0 0)
			(layer "F.Fab")
			(effects
				(font
					(size 1.27 1.27)
				)
			)
		)
		(duplicate_pad_numbers_are_jumpers no)
		(fp_line
			(start -0.7874 -0.4064)
			(end 0.7874 -0.4064)
			(stroke
				(width 0.1524)
				(type default)
			)
			(layer "F.SilkS")
		)
		(fp_line
			(start -0.7874 0.4064)
			(end -0.7874 -0.4064)
			(stroke
				(width 0.1524)
				(type default)
			)
			(layer "F.SilkS")
		)
		(fp_line
			(start 0.7874 -0.4064)
			(end 0.7874 0.4064)
			(stroke
				(width 0.1524)
				(type default)
			)
			(layer "F.SilkS")
		)
		(fp_line
			(start 0.7874 0.4064)
			(end -0.7874 0.4064)
			(stroke
				(width 0.1524)
				(type default)
			)
			(layer "F.SilkS")
		)
		(fp_line
			(start -0.67945 -0.305054)
			(end -0.12065 -0.305054)
			(stroke
				(width 0.1)
				(type default)
			)
			(layer "F.Fab")
		)
		(fp_line
			(start -0.67945 0.3048)
			(end -0.67945 -0.305054)
			(stroke
				(width 0.1)
				(type default)
			)
			(layer "F.Fab")
		)
		(fp_line
			(start -0.12065 -0.305054)
			(end -0.12065 -0.2794)
			(stroke
				(width 0.1)
				(type default)
			)
			(layer "F.Fab")
		)
		(fp_line
			(start -0.12065 -0.2794)
			(end 0.12065 -0.2794)
			(stroke
				(width 0.1)
				(type default)
			)
			(layer "F.Fab")
		)
		(fp_line
			(start -0.12065 0.2794)
			(end -0.12065 0.3048)
			(stroke
				(width 0.1)
				(type default)
			)
			(layer "F.Fab")
		)
		(fp_line
			(start -0.12065 0.3048)
			(end -0.67945 0.3048)
			(stroke
				(width 0.1)
				(type default)
			)
			(layer "F.Fab")
		)
		(fp_line
			(start 0.120396 0.2794)
			(end -0.12065 0.2794)
			(stroke
				(width 0.1)
				(type default)
			)
			(layer "F.Fab")
		)
		(fp_line
			(start 0.120396 0.3048)
			(end 0.120396 0.2794)
			(stroke
				(width 0.1)
				(type default)
			)
			(layer "F.Fab")
		)
		(fp_line
			(start 0.12065 -0.3048)
			(end 0.67945 -0.3048)
			(stroke
				(width 0.1)
				(type default)
			)
			(layer "F.Fab")
		)
		(fp_line
			(start 0.12065 -0.2794)
			(end 0.12065 -0.3048)
			(stroke
				(width 0.1)
				(type default)
			)
			(layer "F.Fab")
		)
		(fp_line
			(start 0.67945 -0.3048)
			(end 0.67945 0.3048)
			(stroke
				(width 0.1)
				(type default)
			)
			(layer "F.Fab")
		)
		(fp_line
			(start 0.67945 0.3048)
			(end 0.120396 0.3048)
			(stroke
				(width 0.1)
				(type default)
			)
			(layer "F.Fab")
		)
		(pad "1" smd circle
			(at -0.40005 0)
			(size 0 0)
			(layers "F.Cu" "F.Mask" "F.Paste")
			(net "P3V3_AUX")
		)
		(pad "2" smd circle
			(at 0.40005 0)
			(size 0 0)
			(layers "F.Cu" "F.Mask" "F.Paste")
			(net "GND")
		)
	)
	(footprint ""
		(layer "F.Cu")
		(at 129.7559 -24.775668 180)
		(property "Reference" "C2284"
			(at 0 0 180)
			(layer "F.SilkS")
			(hide yes)
			(effects
				(font
					(size 1.27 1.27)
				)
			)
		)
		(property "Value" ""
			(at 0 0 180)
			(layer "F.Fab")
			(effects
				(font
					(size 1.27 1.27)
				)
			)
		)
		(duplicate_pad_numbers_are_jumpers no)
		(fp_line
			(start 1.524 0.762)
			(end -1.524 0.762)
			(stroke
				(width 0.1524)
				(type default)
			)
			(layer "F.SilkS")
		)
		(fp_line
			(start 1.524 -0.762)
			(end 1.524 0.762)
			(stroke
				(width 0.1524)
				(type default)
			)
			(layer "F.SilkS")
		)
		(fp_line
			(start -1.524 0.762)
			(end -1.524 -0.762)
			(stroke
				(width 0.1524)
				(type default)
			)
			(layer "F.SilkS")
		)
		(fp_line
			(start -1.524 -0.762)
			(end 1.524 -0.762)
			(stroke
				(width 0.1524)
				(type default)
			)
			(layer "F.SilkS")
		)
		(fp_line
			(start 1.1049 0.724916)
			(end 1.1049 -0.724916)
			(stroke
				(width 0.1)
				(type default)
			)
			(layer "F.Fab")
		)
		(fp_line
			(start 1.1049 -0.724916)
			(end -1.1049 -0.724916)
			(stroke
				(width 0.1)
				(type default)
			)
			(layer "F.Fab")
		)
		(fp_line
			(start -1.1049 0.724916)
			(end 1.1049 0.724916)
			(stroke
				(width 0.1)
				(type default)
			)
			(layer "F.Fab")
		)
		(fp_line
			(start -1.1049 -0.724916)
			(end -1.1049 0.724916)
			(stroke
				(width 0.1)
				(type default)
			)
			(layer "F.Fab")
		)
		(pad "1" smd rect
			(at -0.889 0)
			(size 1.016 1.27)
			(layers "F.Cu" "F.Mask" "F.Paste")
			(net "P3V3_AUX_USB_BUF")
		)
		(pad "2" smd rect
			(at 0.889 0)
			(size 1.016 1.27)
			(layers "F.Cu" "F.Mask" "F.Paste")
			(net "GND")
		)
	)
)
